(kicad_pcb
	(version 20260206)
	(generator "pcbnew")
	(generator_version "10.0")
	(general
		(thickness 1.6)
		(legacy_teardrops no)
	)
	(paper "A4")
	(title_block
		(title "dpb — 14545-sa.0730WZS0815.brd")
		(comment 1 "Honey Badger (Wiwynn) / footprints 507-510 of 1066")
	)
	(layers
		(0 "F.Cu" signal "TOP")
		(4 "In1.Cu" signal "L2GND")
		(6 "In2.Cu" signal "L3")
		(8 "In3.Cu" signal "L4VCC")
		(10 "In4.Cu" signal "L5VCC")
		(12 "In5.Cu" signal "L6")
		(14 "In6.Cu" signal "L7GND")
		(2 "B.Cu" signal "BOTTOM")
		(9 "F.Adhes" user "F.Adhesive")
		(11 "B.Adhes" user "B.Adhesive")
		(13 "F.Paste" user "Package Geometry/Pastemask Top")
		(15 "B.Paste" user "Package Geometry/Pastemask Bottom")
		(5 "F.SilkS" user "Ref Des/Silkscreen Top")
		(7 "B.SilkS" user "Ref Des/Silkscreen Bottom")
		(1 "F.Mask" user "Board Geometry/Soldermask Top")
		(3 "B.Mask" user "Board Geometry/Soldermask Bottom")
		(17 "Dwgs.User" user "User.Drawings")
		(19 "Cmts.User" user "User.Comments")
		(21 "Eco1.User" user "User.Eco1")
		(23 "Eco2.User" user "User.Eco2")
		(25 "Edge.Cuts" user "Board Geometry/Outline")
		(27 "Margin" user)
		(31 "F.CrtYd" user "Package Geometry/Place Bound Top")
		(29 "B.CrtYd" user "Package Geometry/Place Bound Bottom")
		(35 "F.Fab" user "Ref Des/Assembly Top")
		(33 "B.Fab" user "Ref Des/Assembly Bottom")
	)
	(footprint ""
		(layer "F.Cu")
		(at 60.959746 -24.2697 -90)
		(property "Reference" "PR26"
			(at 0 0 270)
			(layer "F.SilkS")
			(hide yes)
			(effects
				(font
					(size 1.27 1.27)
				)
			)
		)
		(property "Value" "100KR2F-L1-GP"
			(at 0.064008 -3.993896 270)
			(unlocked yes)
			(layer "F.Fab")
			(hide yes)
			(effects
				(font
					(size 1.016 1.016)
					(thickness 0.1524)
				)
			)
		)
		(property "Device Type" "R402H16"
			(at 0.064008 -5.517896 270)
			(unlocked yes)
			(layer "F.Fab")
			(hide yes)
			(effects
				(font
					(size 1.016 1.016)
					(thickness 0.1524)
				)
			)
		)
		(duplicate_pad_numbers_are_jumpers no)
		(fp_line
			(start -0.508 -0.9398)
			(end -0.508 0.9398)
			(stroke
				(width 0.1524)
				(type default)
			)
			(layer "F.SilkS")
		)
		(fp_line
			(start 0.508 -0.9398)
			(end -0.508 -0.9398)
			(stroke
				(width 0.1524)
				(type default)
			)
			(layer "F.SilkS")
		)
		(fp_rect
			(start -0.508 0.9398)
			(end 0.508 -0.9398)
			(stroke
				(width 0)
				(type default)
			)
			(fill no)
			(layer "F.CrtYd")
		)
		(fp_rect
			(start -0.508 0.9398)
			(end 0.508 -0.9398)
			(stroke
				(width 0)
				(type default)
			)
			(fill no)
			(layer "F.Fab")
		)
		(pad "1" smd custom
			(at 0 -0.4445 270)
			(size 0.1397 0.1397)
			(layers "F.Cu" "F.Mask" "F.Paste")
			(net "P5VB_PGD")
			(options
				(clearance outline)
				(anchor circle)
			)
			(primitives
				(gr_poly
					(pts
						(arc
							(start -0.1778 -0.2794)
							(mid -0.249642 -0.249642)
							(end -0.2794 -0.1778)
						)
						(arc
							(start -0.2794 0.1778)
							(mid -0.249642 0.249642)
							(end -0.1778 0.2794)
						)
						(arc
							(start 0.1778 0.2794)
							(mid 0.249642 0.249642)
							(end 0.2794 0.1778)
						)
						(arc
							(start 0.2794 -0.1778)
							(mid 0.249642 -0.249642)
							(end 0.1778 -0.2794)
						)
					)
					(width 0)
					(fill yes)
				)
			)
		)
		(pad "2" smd custom
			(at 0 0.4445 270)
			(size 0.1397 0.1397)
			(layers "F.Cu" "F.Mask" "F.Paste")
			(net "P5VB_MODE_PG")
			(options
				(clearance outline)
				(anchor circle)
			)
			(primitives
				(gr_poly
					(pts
						(arc
							(start -0.1778 -0.2794)
							(mid -0.249642 -0.249642)
							(end -0.2794 -0.1778)
						)
						(arc
							(start -0.2794 0.1778)
							(mid -0.249642 0.249642)
							(end -0.1778 0.2794)
						)
						(arc
							(start 0.1778 0.2794)
							(mid 0.249642 0.249642)
							(end 0.2794 0.1778)
						)
						(arc
							(start 0.2794 -0.1778)
							(mid 0.249642 -0.249642)
							(end 0.1778 -0.2794)
						)
					)
					(width 0)
					(fill yes)
				)
			)
		)
	)
	(footprint ""
		(layer "F.Cu")
		(at 26.02103 -139.950952 90)
		(property "Reference" "C310"
			(at 0 0 90)
			(layer "F.SilkS")
			(hide yes)
			(effects
				(font
					(size 1.27 1.27)
				)
			)
		)
		(property "Value" "SCD01U50V2KX-1GP"
			(at 1.1811 -2.7051 90)
			(unlocked yes)
			(layer "F.Fab")
			(hide yes)
			(effects
				(font
					(size 1.016 1.016)
					(thickness 0.1524)
				)
			)
		)
		(property "Device Type" "C402H22"
			(at 1.1811 -4.2291 90)
			(unlocked yes)
			(layer "F.Fab")
			(hide yes)
			(effects
				(font
					(size 1.016 1.016)
					(thickness 0.1524)
				)
			)
		)
		(duplicate_pad_numbers_are_jumpers no)
		(fp_rect
			(start -0.4318 0.9525)
			(end 0.4318 -0.9525)
			(stroke
				(width 0)
				(type default)
			)
			(fill no)
			(layer "F.CrtYd")
		)
		(fp_rect
			(start -0.4318 0.9525)
			(end 0.4318 -0.9525)
			(stroke
				(width 0)
				(type default)
			)
			(fill no)
			(layer "F.Fab")
		)
		(pad "1" smd custom
			(at 0 -0.4445 90)
			(size 0.1524 0.1524)
			(layers "F.Cu" "F.Mask" "F.Paste")
			(net "SAS2X28_DRIVE_RX_N_A13")
			(options
				(clearance outline)
				(anchor circle)
			)
			(primitives
				(gr_poly
					(pts
						(arc
							(start 0.3048 -0.2032)
							(mid 0.275042 -0.275042)
							(end 0.2032 -0.3048)
						)
						(arc
							(start -0.2032 -0.3048)
							(mid -0.275042 -0.275042)
							(end -0.3048 -0.2032)
						)
						(arc
							(start -0.3048 0.2032)
							(mid -0.275042 0.275042)
							(end -0.2032 0.3048)
						)
						(arc
							(start 0.2032 0.3048)
							(mid 0.275042 0.275042)
							(end 0.3048 0.2032)
						)
					)
					(width 0)
					(fill yes)
				)
			)
		)
		(pad "2" smd custom
			(at 0 0.4445 90)
			(size 0.1524 0.1524)
			(layers "F.Cu" "F.Mask" "F.Paste")
			(net "SAS2X28_A_HDD13_RX_-")
			(options
				(clearance outline)
				(anchor circle)
			)
			(primitives
				(gr_poly
					(pts
						(arc
							(start 0.3048 -0.2032)
							(mid 0.275042 -0.275042)
							(end 0.2032 -0.3048)
						)
						(arc
							(start -0.2032 -0.3048)
							(mid -0.275042 -0.275042)
							(end -0.3048 -0.2032)
						)
						(arc
							(start -0.3048 0.2032)
							(mid -0.275042 0.275042)
							(end -0.2032 0.3048)
						)
						(arc
							(start 0.2032 0.3048)
							(mid 0.275042 0.275042)
							(end 0.3048 0.2032)
						)
					)
					(width 0)
					(fill yes)
				)
			)
		)
	)
	(footprint ""
		(layer "F.Cu")
		(at 29.362146 -373.4435 180)
		(property "Reference" "R313"
			(at 0 0 180)
			(layer "F.SilkS")
			(hide yes)
			(effects
				(font
					(size 1.27 1.27)
				)
			)
		)
		(property "Value" "4K7R2J-2-GP"
			(at 0.064008 -3.993896 180)
			(unlocked yes)
			(layer "F.Fab")
			(hide yes)
			(effects
				(font
					(size 1.016 1.016)
					(thickness 0.1524)
				)
			)
		)
		(property "Device Type" "R402H16"
			(at 0.064008 -5.517896 180)
			(unlocked yes)
			(layer "F.Fab")
			(hide yes)
			(effects
				(font
					(size 1.016 1.016)
					(thickness 0.1524)
				)
			)
		)
		(duplicate_pad_numbers_are_jumpers no)
		(fp_line
			(start 0.508 -0.9398)
			(end -0.508 -0.9398)
			(stroke
				(width 0.1524)
				(type default)
			)
			(layer "F.SilkS")
		)
		(fp_line
			(start -0.508 -0.9398)
			(end -0.508 0.9398)
			(stroke
				(width 0.1524)
				(type default)
			)
			(layer "F.SilkS")
		)
		(fp_rect
			(start -0.508 0.9398)
			(end 0.508 -0.9398)
			(stroke
				(width 0)
				(type default)
			)
			(fill no)
			(layer "F.CrtYd")
		)
		(fp_rect
			(start -0.508 0.9398)
			(end 0.508 -0.9398)
			(stroke
				(width 0)
				(type default)
			)
			(fill no)
			(layer "F.Fab")
		)
		(pad "1" smd custom
			(at 0 -0.4445 180)
			(size 0.1397 0.1397)
			(layers "F.Cu" "F.Mask" "F.Paste")
			(net "P3V3")
			(options
				(clearance outline)
				(anchor circle)
			)
			(primitives
				(gr_poly
					(pts
						(arc
							(start -0.1778 -0.2794)
							(mid -0.249642 -0.249642)
							(end -0.2794 -0.1778)
						)
						(arc
							(start -0.2794 0.1778)
							(mid -0.249642 0.249642)
							(end -0.1778 0.2794)
						)
						(arc
							(start 0.1778 0.2794)
							(mid 0.249642 0.249642)
							(end 0.2794 0.1778)
						)
						(arc
							(start 0.2794 -0.1778)
							(mid 0.249642 -0.249642)
							(end 0.1778 -0.2794)
						)
					)
					(width 0)
					(fill yes)
				)
			)
		)
		(pad "2" smd custom
			(at 0 0.4445 180)
			(size 0.1397 0.1397)
			(layers "F.Cu" "F.Mask" "F.Paste")
			(net "I2C_B_TMP1_A0")
			(options
				(clearance outline)
				(anchor circle)
			)
			(primitives
				(gr_poly
					(pts
						(arc
							(start -0.1778 -0.2794)
							(mid -0.249642 -0.249642)
							(end -0.2794 -0.1778)
						)
						(arc
							(start -0.2794 0.1778)
							(mid -0.249642 0.249642)
							(end -0.1778 0.2794)
						)
						(arc
							(start 0.1778 0.2794)
							(mid 0.249642 0.249642)
							(end 0.2794 0.1778)
						)
						(arc
							(start 0.2794 -0.1778)
							(mid 0.249642 -0.249642)
							(end 0.1778 -0.2794)
						)
					)
					(width 0)
					(fill yes)
				)
			)
		)
	)
	(footprint ""
		(layer "F.Cu")
		(at 217.799412 -57.130696 -90)
		(property "Reference" "C166"
			(at 0 0 270)
			(layer "F.SilkS")
			(hide yes)
			(effects
				(font
					(size 1.27 1.27)
				)
			)
		)
		(property "Value" "SCD01U50V2KX-1GP"
			(at 1.1811 -2.7051 270)
			(unlocked yes)
			(layer "F.Fab")
			(hide yes)
			(effects
				(font
					(size 1.016 1.016)
					(thickness 0.1524)
				)
			)
		)
		(property "Device Type" "C402H22"
			(at 1.1811 -4.2291 270)
			(unlocked yes)
			(layer "F.Fab")
			(hide yes)
			(effects
				(font
					(size 1.016 1.016)
					(thickness 0.1524)
				)
			)
		)
		(duplicate_pad_numbers_are_jumpers no)
		(fp_rect
			(start -0.4318 0.9525)
			(end 0.4318 -0.9525)
			(stroke
				(width 0)
				(type default)
			)
			(fill no)
			(layer "F.CrtYd")
		)
		(fp_rect
			(start -0.4318 0.9525)
			(end 0.4318 -0.9525)
			(stroke
				(width 0)
				(type default)
			)
			(fill no)
			(layer "F.Fab")
		)
		(pad "1" smd custom
			(at 0 -0.4445 270)
			(size 0.1524 0.1524)
			(layers "F.Cu" "F.Mask" "F.Paste")
			(net "SAS2X28_DRIVE_RX_N_A4")
			(options
				(clearance outline)
				(anchor circle)
			)
			(primitives
				(gr_poly
					(pts
						(arc
							(start 0.3048 -0.2032)
							(mid 0.275042 -0.275042)
							(end 0.2032 -0.3048)
						)
						(arc
							(start -0.2032 -0.3048)
							(mid -0.275042 -0.275042)
							(end -0.3048 -0.2032)
						)
						(arc
							(start -0.3048 0.2032)
							(mid -0.275042 0.275042)
							(end -0.2032 0.3048)
						)
						(arc
							(start 0.2032 0.3048)
							(mid 0.275042 0.275042)
							(end 0.3048 0.2032)
						)
					)
					(width 0)
					(fill yes)
				)
			)
		)
		(pad "2" smd custom
			(at 0 0.4445 270)
			(size 0.1524 0.1524)
			(layers "F.Cu" "F.Mask" "F.Paste")
			(net "SAS2X28_A_HDD4_RX_-")
			(options
				(clearance outline)
				(anchor circle)
			)
			(primitives
				(gr_poly
					(pts
						(arc
							(start 0.3048 -0.2032)
							(mid 0.275042 -0.275042)
							(end 0.2032 -0.3048)
						)
						(arc
							(start -0.2032 -0.3048)
							(mid -0.275042 -0.275042)
							(end -0.3048 -0.2032)
						)
						(arc
							(start -0.3048 0.2032)
							(mid -0.275042 0.275042)
							(end -0.2032 0.3048)
						)
						(arc
							(start 0.2032 0.3048)
							(mid 0.275042 0.275042)
							(end 0.3048 0.2032)
						)
					)
					(width 0)
					(fill yes)
				)
			)
		)
	)
)
